(kicad_pcb
	(version 20260206)
	(generator "pcbnew")
	(generator_version "10.0")
	(general
		(thickness 1.6)
		(legacy_teardrops no)
	)
	(paper "A4")
	(title_block
		(title "03242023_DA0F0TMBIJ0_F0T_Motherboard_J_brd_V01_OCP.brd")
		(comment 1 "Grand Teton / footprints 3226-3232 of 6105")
	)
	(layers
		(0 "F.Cu" signal "TOP")
		(4 "In1.Cu" signal "GND")
		(6 "In2.Cu" signal "IN1")
		(8 "In3.Cu" signal "GND1")
		(10 "In4.Cu" signal "IN2")
		(12 "In5.Cu" signal "GND2")
		(14 "In6.Cu" signal "IN3")
		(16 "In7.Cu" signal "GND3")
		(18 "In8.Cu" signal "VCC")
		(20 "In9.Cu" signal "VCC1")
		(22 "In10.Cu" signal "GND4")
		(24 "In11.Cu" signal "IN4")
		(26 "In12.Cu" signal "GND5")
		(28 "In13.Cu" signal "IN5")
		(30 "In14.Cu" signal "GND6")
		(32 "In15.Cu" signal "IN6")
		(34 "In16.Cu" signal "GND7")
		(2 "B.Cu" signal "BOTTOM")
		(9 "F.Adhes" user "F.Adhesive")
		(11 "B.Adhes" user "B.Adhesive")
		(13 "F.Paste" user "Package Geometry/Pastemask Top")
		(15 "B.Paste" user "Package Geometry/Pastemask Bottom")
		(5 "F.SilkS" user "Ref Des/Silkscreen Top")
		(7 "B.SilkS" user "Ref Des/Silkscreen Bottom")
		(1 "F.Mask" user "Board Geometry/Soldermask Top")
		(3 "B.Mask" user "Board Geometry/Soldermask Bottom")
		(17 "Dwgs.User" user "User.Drawings")
		(19 "Cmts.User" user "User.Comments")
		(21 "Eco1.User" user "User.Eco1")
		(23 "Eco2.User" user "User.Eco2")
		(25 "Edge.Cuts" user "Board Geometry/Outline")
		(27 "Margin" user)
		(31 "F.CrtYd" user "Package Geometry/Place Bound Top")
		(29 "B.CrtYd" user "Package Geometry/Place Bound Bottom")
		(35 "F.Fab" user "Ref Des/Assembly Top")
		(33 "B.Fab" user "Ref Des/Assembly Bottom")
	)
	(footprint ""
		(layer "F.Cu")
		(at 147.447 -130.647948)
		(property "Reference" "R4604"
			(at 0 0 0)
			(layer "F.SilkS")
			(hide yes)
			(effects
				(font
					(size 1.27 1.27)
				)
			)
		)
		(property "Value" ""
			(at 0 0 0)
			(layer "F.Fab")
			(effects
				(font
					(size 1.27 1.27)
				)
			)
		)
		(duplicate_pad_numbers_are_jumpers no)
		(fp_line
			(start -0.7874 -0.4064)
			(end 0.7874 -0.4064)
			(stroke
				(width 0.1524)
				(type default)
			)
			(layer "F.SilkS")
		)
		(fp_line
			(start -0.7874 0.4064)
			(end -0.7874 -0.4064)
			(stroke
				(width 0.1524)
				(type default)
			)
			(layer "F.SilkS")
		)
		(fp_line
			(start 0.7874 -0.4064)
			(end 0.7874 0.4064)
			(stroke
				(width 0.1524)
				(type default)
			)
			(layer "F.SilkS")
		)
		(fp_line
			(start 0.7874 0.4064)
			(end -0.7874 0.4064)
			(stroke
				(width 0.1524)
				(type default)
			)
			(layer "F.SilkS")
		)
		(fp_line
			(start -0.67945 -0.305054)
			(end -0.12065 -0.305054)
			(stroke
				(width 0.1)
				(type default)
			)
			(layer "F.Fab")
		)
		(fp_line
			(start -0.67945 0.3048)
			(end -0.67945 -0.305054)
			(stroke
				(width 0.1)
				(type default)
			)
			(layer "F.Fab")
		)
		(fp_line
			(start -0.12065 -0.305054)
			(end -0.12065 -0.2794)
			(stroke
				(width 0.1)
				(type default)
			)
			(layer "F.Fab")
		)
		(fp_line
			(start -0.12065 -0.2794)
			(end 0.12065 -0.2794)
			(stroke
				(width 0.1)
				(type default)
			)
			(layer "F.Fab")
		)
		(fp_line
			(start -0.12065 0.2794)
			(end -0.12065 0.3048)
			(stroke
				(width 0.1)
				(type default)
			)
			(layer "F.Fab")
		)
		(fp_line
			(start -0.12065 0.3048)
			(end -0.67945 0.3048)
			(stroke
				(width 0.1)
				(type default)
			)
			(layer "F.Fab")
		)
		(fp_line
			(start 0.120396 0.2794)
			(end -0.12065 0.2794)
			(stroke
				(width 0.1)
				(type default)
			)
			(layer "F.Fab")
		)
		(fp_line
			(start 0.120396 0.3048)
			(end 0.120396 0.2794)
			(stroke
				(width 0.1)
				(type default)
			)
			(layer "F.Fab")
		)
		(fp_line
			(start 0.12065 -0.3048)
			(end 0.67945 -0.3048)
			(stroke
				(width 0.1)
				(type default)
			)
			(layer "F.Fab")
		)
		(fp_line
			(start 0.12065 -0.2794)
			(end 0.12065 -0.3048)
			(stroke
				(width 0.1)
				(type default)
			)
			(layer "F.Fab")
		)
		(fp_line
			(start 0.67945 -0.3048)
			(end 0.67945 0.3048)
			(stroke
				(width 0.1)
				(type default)
			)
			(layer "F.Fab")
		)
		(fp_line
			(start 0.67945 0.3048)
			(end 0.120396 0.3048)
			(stroke
				(width 0.1)
				(type default)
			)
			(layer "F.Fab")
		)
		(pad "1" smd circle
			(at -0.40005 0)
			(size 0 0)
			(layers "F.Cu" "F.Mask" "F.Paste")
			(net "P3V3_AUX")
		)
		(pad "2" smd circle
			(at 0.40005 0)
			(size 0 0)
			(layers "F.Cu" "F.Mask" "F.Paste")
			(net "PWRGD_PS_PWROK_PLD_N")
		)
	)
	(footprint ""
		(layer "F.Cu")
		(at 418.26053 -402.371052 -90)
		(property "Reference" "C964"
			(at 0 0 270)
			(layer "F.SilkS")
			(hide yes)
			(effects
				(font
					(size 1.27 1.27)
				)
			)
		)
		(property "Value" ""
			(at 0 0 270)
			(layer "F.Fab")
			(effects
				(font
					(size 1.27 1.27)
				)
			)
		)
		(duplicate_pad_numbers_are_jumpers no)
		(fp_line
			(start -0.299974 0.150114)
			(end -0.299974 -0.150114)
			(stroke
				(width 0.1)
				(type default)
			)
			(layer "F.Fab")
		)
		(fp_line
			(start 0.299974 0.150114)
			(end -0.299974 0.150114)
			(stroke
				(width 0.1)
				(type default)
			)
			(layer "F.Fab")
		)
		(fp_line
			(start -0.299974 -0.150114)
			(end 0.299974 -0.150114)
			(stroke
				(width 0.1)
				(type default)
			)
			(layer "F.Fab")
		)
		(fp_line
			(start 0.299974 -0.150114)
			(end 0.299974 0.150114)
			(stroke
				(width 0.1)
				(type default)
			)
			(layer "F.Fab")
		)
		(pad "1" smd rect
			(at -0.2667 0 270)
			(size 0.3048 0.381)
			(layers "F.Cu" "F.Mask" "F.Paste")
			(net "P5E_CPU0_PE2_TX_C_DN<0>")
		)
		(pad "2" smd rect
			(at 0.2667 0 270)
			(size 0.3048 0.381)
			(layers "F.Cu" "F.Mask" "F.Paste")
			(net "P5E_CPU0_PE2_TX_DN<0>")
		)
	)
	(footprint ""
		(layer "F.Cu")
		(at 193.60388 -101.145848 180)
		(property "Reference" "R3046"
			(at 0 0 180)
			(layer "F.SilkS")
			(hide yes)
			(effects
				(font
					(size 1.27 1.27)
				)
			)
		)
		(property "Value" ""
			(at 0 0 180)
			(layer "F.Fab")
			(effects
				(font
					(size 1.27 1.27)
				)
			)
		)
		(duplicate_pad_numbers_are_jumpers no)
		(fp_line
			(start 0.7874 0.4064)
			(end -0.7874 0.4064)
			(stroke
				(width 0.1524)
				(type default)
			)
			(layer "F.SilkS")
		)
		(fp_line
			(start 0.7874 -0.4064)
			(end 0.7874 0.4064)
			(stroke
				(width 0.1524)
				(type default)
			)
			(layer "F.SilkS")
		)
		(fp_line
			(start -0.7874 0.4064)
			(end -0.7874 -0.4064)
			(stroke
				(width 0.1524)
				(type default)
			)
			(layer "F.SilkS")
		)
		(fp_line
			(start -0.7874 -0.4064)
			(end 0.7874 -0.4064)
			(stroke
				(width 0.1524)
				(type default)
			)
			(layer "F.SilkS")
		)
		(fp_line
			(start 0.67945 0.3048)
			(end 0.120396 0.3048)
			(stroke
				(width 0.1)
				(type default)
			)
			(layer "F.Fab")
		)
		(fp_line
			(start 0.67945 -0.3048)
			(end 0.67945 0.3048)
			(stroke
				(width 0.1)
				(type default)
			)
			(layer "F.Fab")
		)
		(fp_line
			(start 0.12065 -0.2794)
			(end 0.12065 -0.3048)
			(stroke
				(width 0.1)
				(type default)
			)
			(layer "F.Fab")
		)
		(fp_line
			(start 0.12065 -0.3048)
			(end 0.67945 -0.3048)
			(stroke
				(width 0.1)
				(type default)
			)
			(layer "F.Fab")
		)
		(fp_line
			(start 0.120396 0.3048)
			(end 0.120396 0.2794)
			(stroke
				(width 0.1)
				(type default)
			)
			(layer "F.Fab")
		)
		(fp_line
			(start 0.120396 0.2794)
			(end -0.12065 0.2794)
			(stroke
				(width 0.1)
				(type default)
			)
			(layer "F.Fab")
		)
		(fp_line
			(start -0.12065 0.3048)
			(end -0.67945 0.3048)
			(stroke
				(width 0.1)
				(type default)
			)
			(layer "F.Fab")
		)
		(fp_line
			(start -0.12065 0.2794)
			(end -0.12065 0.3048)
			(stroke
				(width 0.1)
				(type default)
			)
			(layer "F.Fab")
		)
		(fp_line
			(start -0.12065 -0.2794)
			(end 0.12065 -0.2794)
			(stroke
				(width 0.1)
				(type default)
			)
			(layer "F.Fab")
		)
		(fp_line
			(start -0.12065 -0.305054)
			(end -0.12065 -0.2794)
			(stroke
				(width 0.1)
				(type default)
			)
			(layer "F.Fab")
		)
		(fp_line
			(start -0.67945 0.3048)
			(end -0.67945 -0.305054)
			(stroke
				(width 0.1)
				(type default)
			)
			(layer "F.Fab")
		)
		(fp_line
			(start -0.67945 -0.305054)
			(end -0.12065 -0.305054)
			(stroke
				(width 0.1)
				(type default)
			)
			(layer "F.Fab")
		)
		(pad "1" smd circle
			(at -0.40005 0 180)
			(size 0 0)
			(layers "F.Cu" "F.Mask" "F.Paste")
			(net "FM_UV_ADR_TRIGGER_N")
		)
		(pad "2" smd circle
			(at 0.40005 0 180)
			(size 0 0)
			(layers "F.Cu" "F.Mask" "F.Paste")
			(net "FM_UV_ADR_TRIGGER_R_N")
		)
	)
	(footprint ""
		(layer "F.Cu")
		(at 236.599984 -245.411498 -90)
		(property "Reference" "R4079"
			(at 0 0 270)
			(layer "F.SilkS")
			(hide yes)
			(effects
				(font
					(size 1.27 1.27)
				)
			)
		)
		(property "Value" ""
			(at 0 0 270)
			(layer "F.Fab")
			(effects
				(font
					(size 1.27 1.27)
				)
			)
		)
		(duplicate_pad_numbers_are_jumpers no)
		(fp_line
			(start -0.7874 0.4064)
			(end -0.7874 -0.4064)
			(stroke
				(width 0.1524)
				(type default)
			)
			(layer "F.SilkS")
		)
		(fp_line
			(start 0.7874 0.4064)
			(end -0.7874 0.4064)
			(stroke
				(width 0.1524)
				(type default)
			)
			(layer "F.SilkS")
		)
		(fp_line
			(start -0.7874 -0.4064)
			(end 0.7874 -0.4064)
			(stroke
				(width 0.1524)
				(type default)
			)
			(layer "F.SilkS")
		)
		(fp_line
			(start 0.7874 -0.4064)
			(end 0.7874 0.4064)
			(stroke
				(width 0.1524)
				(type default)
			)
			(layer "F.SilkS")
		)
		(fp_line
			(start -0.67945 0.3048)
			(end -0.67945 -0.305054)
			(stroke
				(width 0.1)
				(type default)
			)
			(layer "F.Fab")
		)
		(fp_line
			(start -0.12065 0.3048)
			(end -0.67945 0.3048)
			(stroke
				(width 0.1)
				(type default)
			)
			(layer "F.Fab")
		)
		(fp_line
			(start 0.120396 0.3048)
			(end 0.120396 0.2794)
			(stroke
				(width 0.1)
				(type default)
			)
			(layer "F.Fab")
		)
		(fp_line
			(start 0.67945 0.3048)
			(end 0.120396 0.3048)
			(stroke
				(width 0.1)
				(type default)
			)
			(layer "F.Fab")
		)
		(fp_line
			(start -0.12065 0.2794)
			(end -0.12065 0.3048)
			(stroke
				(width 0.1)
				(type default)
			)
			(layer "F.Fab")
		)
		(fp_line
			(start 0.120396 0.2794)
			(end -0.12065 0.2794)
			(stroke
				(width 0.1)
				(type default)
			)
			(layer "F.Fab")
		)
		(fp_line
			(start -0.12065 -0.2794)
			(end 0.12065 -0.2794)
			(stroke
				(width 0.1)
				(type default)
			)
			(layer "F.Fab")
		)
		(fp_line
			(start 0.12065 -0.2794)
			(end 0.12065 -0.3048)
			(stroke
				(width 0.1)
				(type default)
			)
			(layer "F.Fab")
		)
		(fp_line
			(start 0.12065 -0.3048)
			(end 0.67945 -0.3048)
			(stroke
				(width 0.1)
				(type default)
			)
			(layer "F.Fab")
		)
		(fp_line
			(start 0.67945 -0.3048)
			(end 0.67945 0.3048)
			(stroke
				(width 0.1)
				(type default)
			)
			(layer "F.Fab")
		)
		(fp_line
			(start -0.67945 -0.305054)
			(end -0.12065 -0.305054)
			(stroke
				(width 0.1)
				(type default)
			)
			(layer "F.Fab")
		)
		(fp_line
			(start -0.12065 -0.305054)
			(end -0.12065 -0.2794)
			(stroke
				(width 0.1)
				(type default)
			)
			(layer "F.Fab")
		)
		(pad "1" smd circle
			(at -0.40005 0 270)
			(size 0 0)
			(layers "F.Cu" "F.Mask" "F.Paste")
			(net "FG_SS_EN")
		)
		(pad "2" smd circle
			(at 0.40005 0 270)
			(size 0 0)
			(layers "F.Cu" "F.Mask" "F.Paste")
			(net "GND")
		)
	)
	(footprint ""
		(layer "F.Cu")
		(at 166.17823 -73.754234)
		(property "Reference" "R2905"
			(at 0 0 0)
			(layer "F.SilkS")
			(hide yes)
			(effects
				(font
					(size 1.27 1.27)
				)
			)
		)
		(property "Value" ""
			(at 0 0 0)
			(layer "F.Fab")
			(effects
				(font
					(size 1.27 1.27)
				)
			)
		)
		(duplicate_pad_numbers_are_jumpers no)
		(fp_line
			(start -0.7874 -0.4064)
			(end 0.7874 -0.4064)
			(stroke
				(width 0.1524)
				(type default)
			)
			(layer "F.SilkS")
		)
		(fp_line
			(start -0.7874 0.4064)
			(end -0.7874 -0.4064)
			(stroke
				(width 0.1524)
				(type default)
			)
			(layer "F.SilkS")
		)
		(fp_line
			(start 0.7874 -0.4064)
			(end 0.7874 0.4064)
			(stroke
				(width 0.1524)
				(type default)
			)
			(layer "F.SilkS")
		)
		(fp_line
			(start 0.7874 0.4064)
			(end -0.7874 0.4064)
			(stroke
				(width 0.1524)
				(type default)
			)
			(layer "F.SilkS")
		)
		(fp_line
			(start -0.67945 -0.305054)
			(end -0.12065 -0.305054)
			(stroke
				(width 0.1)
				(type default)
			)
			(layer "F.Fab")
		)
		(fp_line
			(start -0.67945 0.3048)
			(end -0.67945 -0.305054)
			(stroke
				(width 0.1)
				(type default)
			)
			(layer "F.Fab")
		)
		(fp_line
			(start -0.12065 -0.305054)
			(end -0.12065 -0.2794)
			(stroke
				(width 0.1)
				(type default)
			)
			(layer "F.Fab")
		)
		(fp_line
			(start -0.12065 -0.2794)
			(end 0.12065 -0.2794)
			(stroke
				(width 0.1)
				(type default)
			)
			(layer "F.Fab")
		)
		(fp_line
			(start -0.12065 0.2794)
			(end -0.12065 0.3048)
			(stroke
				(width 0.1)
				(type default)
			)
			(layer "F.Fab")
		)
		(fp_line
			(start -0.12065 0.3048)
			(end -0.67945 0.3048)
			(stroke
				(width 0.1)
				(type default)
			)
			(layer "F.Fab")
		)
		(fp_line
			(start 0.120396 0.2794)
			(end -0.12065 0.2794)
			(stroke
				(width 0.1)
				(type default)
			)
			(layer "F.Fab")
		)
		(fp_line
			(start 0.120396 0.3048)
			(end 0.120396 0.2794)
			(stroke
				(width 0.1)
				(type default)
			)
			(layer "F.Fab")
		)
		(fp_line
			(start 0.12065 -0.3048)
			(end 0.67945 -0.3048)
			(stroke
				(width 0.1)
				(type default)
			)
			(layer "F.Fab")
		)
		(fp_line
			(start 0.12065 -0.2794)
			(end 0.12065 -0.3048)
			(stroke
				(width 0.1)
				(type default)
			)
			(layer "F.Fab")
		)
		(fp_line
			(start 0.67945 -0.3048)
			(end 0.67945 0.3048)
			(stroke
				(width 0.1)
				(type default)
			)
			(layer "F.Fab")
		)
		(fp_line
			(start 0.67945 0.3048)
			(end 0.120396 0.3048)
			(stroke
				(width 0.1)
				(type default)
			)
			(layer "F.Fab")
		)
		(pad "1" smd circle
			(at -0.40005 0)
			(size 0 0)
			(layers "F.Cu" "F.Mask" "F.Paste")
			(net "RST_SMB_SWITCH_N")
		)
		(pad "2" smd circle
			(at 0.40005 0)
			(size 0 0)
			(layers "F.Cu" "F.Mask" "F.Paste")
			(net "RST_SMB_SWITCH_R_N")
		)
	)
	(footprint ""
		(layer "F.Cu")
		(at 461.445356 -382.077214)
		(property "Reference" "R2316"
			(at 0 0 0)
			(layer "F.SilkS")
			(hide yes)
			(effects
				(font
					(size 1.27 1.27)
				)
			)
		)
		(property "Value" ""
			(at 0 0 0)
			(layer "F.Fab")
			(effects
				(font
					(size 1.27 1.27)
				)
			)
		)
		(duplicate_pad_numbers_are_jumpers no)
		(fp_line
			(start -0.7874 -0.4064)
			(end 0.7874 -0.4064)
			(stroke
				(width 0.1524)
				(type default)
			)
			(layer "F.SilkS")
		)
		(fp_line
			(start -0.7874 0.4064)
			(end -0.7874 -0.4064)
			(stroke
				(width 0.1524)
				(type default)
			)
			(layer "F.SilkS")
		)
		(fp_line
			(start 0.7874 -0.4064)
			(end 0.7874 0.4064)
			(stroke
				(width 0.1524)
				(type default)
			)
			(layer "F.SilkS")
		)
		(fp_line
			(start 0.7874 0.4064)
			(end -0.7874 0.4064)
			(stroke
				(width 0.1524)
				(type default)
			)
			(layer "F.SilkS")
		)
		(fp_line
			(start -0.67945 -0.305054)
			(end -0.12065 -0.305054)
			(stroke
				(width 0.1)
				(type default)
			)
			(layer "F.Fab")
		)
		(fp_line
			(start -0.67945 0.3048)
			(end -0.67945 -0.305054)
			(stroke
				(width 0.1)
				(type default)
			)
			(layer "F.Fab")
		)
		(fp_line
			(start -0.12065 -0.305054)
			(end -0.12065 -0.2794)
			(stroke
				(width 0.1)
				(type default)
			)
			(layer "F.Fab")
		)
		(fp_line
			(start -0.12065 -0.2794)
			(end 0.12065 -0.2794)
			(stroke
				(width 0.1)
				(type default)
			)
			(layer "F.Fab")
		)
		(fp_line
			(start -0.12065 0.2794)
			(end -0.12065 0.3048)
			(stroke
				(width 0.1)
				(type default)
			)
			(layer "F.Fab")
		)
		(fp_line
			(start -0.12065 0.3048)
			(end -0.67945 0.3048)
			(stroke
				(width 0.1)
				(type default)
			)
			(layer "F.Fab")
		)
		(fp_line
			(start 0.120396 0.2794)
			(end -0.12065 0.2794)
			(stroke
				(width 0.1)
				(type default)
			)
			(layer "F.Fab")
		)
		(fp_line
			(start 0.120396 0.3048)
			(end 0.120396 0.2794)
			(stroke
				(width 0.1)
				(type default)
			)
			(layer "F.Fab")
		)
		(fp_line
			(start 0.12065 -0.3048)
			(end 0.67945 -0.3048)
			(stroke
				(width 0.1)
				(type default)
			)
			(layer "F.Fab")
		)
		(fp_line
			(start 0.12065 -0.2794)
			(end 0.12065 -0.3048)
			(stroke
				(width 0.1)
				(type default)
			)
			(layer "F.Fab")
		)
		(fp_line
			(start 0.67945 -0.3048)
			(end 0.67945 0.3048)
			(stroke
				(width 0.1)
				(type default)
			)
			(layer "F.Fab")
		)
		(fp_line
			(start 0.67945 0.3048)
			(end 0.120396 0.3048)
			(stroke
				(width 0.1)
				(type default)
			)
			(layer "F.Fab")
		)
		(pad "1" smd circle
			(at -0.40005 0)
			(size 0 0)
			(layers "F.Cu" "F.Mask" "F.Paste")
			(net "PWRGD_P5V_AUX_R")
		)
		(pad "2" smd circle
			(at 0.40005 0)
			(size 0 0)
			(layers "F.Cu" "F.Mask" "F.Paste")
			(net "PWRGD_P5V_AUX")
		)
	)
	(footprint ""
		(layer "F.Cu")
		(at 22.010878 -16.099536 90)
		(property "Reference" "C810"
			(at 0 0 90)
			(layer "F.SilkS")
			(hide yes)
			(effects
				(font
					(size 1.27 1.27)
				)
			)
		)
		(property "Value" ""
			(at 0 0 90)
			(layer "F.Fab")
			(effects
				(font
					(size 1.27 1.27)
				)
			)
		)
		(duplicate_pad_numbers_are_jumpers no)
		(fp_line
			(start 0.299974 -0.150114)
			(end 0.299974 0.150114)
			(stroke
				(width 0.1)
				(type default)
			)
			(layer "F.Fab")
		)
		(fp_line
			(start -0.299974 -0.150114)
			(end 0.299974 -0.150114)
			(stroke
				(width 0.1)
				(type default)
			)
			(layer "F.Fab")
		)
		(fp_line
			(start 0.299974 0.150114)
			(end -0.299974 0.150114)
			(stroke
				(width 0.1)
				(type default)
			)
			(layer "F.Fab")
		)
		(fp_line
			(start -0.299974 0.150114)
			(end -0.299974 -0.150114)
			(stroke
				(width 0.1)
				(type default)
			)
			(layer "F.Fab")
		)
		(pad "1" smd rect
			(at -0.2667 0 90)
			(size 0.3048 0.381)
			(layers "F.Cu" "F.Mask" "F.Paste")
			(net "P5E_CPU1_PE1_TX_C_DN<13>")
		)
		(pad "2" smd rect
			(at 0.2667 0 90)
			(size 0.3048 0.381)
			(layers "F.Cu" "F.Mask" "F.Paste")
			(net "P5E_CPU1_PE1_TX_DN<13>")
		)
	)
)
